(kicad_pcb
	(version 20260206)
	(generator "pcbnew")
	(generator_version "10.0")
	(general
		(thickness 1.6)
		(legacy_teardrops no)
	)
	(paper "A4")
	(title_block
		(title "Bryce Canyon_F.DPB_16315-1-OCP.brd")
		(comment 1 "Bryce Canyon / footprint 2183 of 2223 (IO2), pads 197-202 of 202")
	)
	(layers
		(0 "F.Cu" signal "TOP")
		(4 "In1.Cu" signal "L2GND")
		(6 "In2.Cu" signal "L3")
		(8 "In3.Cu" signal "L4GND")
		(10 "In4.Cu" signal "L5")
		(12 "In5.Cu" signal "L6VCC")
		(14 "In6.Cu" signal "L7VCC")
		(16 "In7.Cu" signal "L8")
		(18 "In8.Cu" signal "L9GND")
		(20 "In9.Cu" signal "L10")
		(22 "In10.Cu" signal "L11GND")
		(2 "B.Cu" signal "BOTTOM")
		(9 "F.Adhes" user "F.Adhesive")
		(11 "B.Adhes" user "B.Adhesive")
		(13 "F.Paste" user "Package Geometry/Pastemask Top")
		(15 "B.Paste" user "Package Geometry/Pastemask Bottom")
		(5 "F.SilkS" user "Ref Des/Silkscreen Top")
		(7 "B.SilkS" user "Ref Des/Silkscreen Bottom")
		(1 "F.Mask" user "Board Geometry/Soldermask Top")
		(3 "B.Mask" user "Board Geometry/Soldermask Bottom")
		(17 "Dwgs.User" user "User.Drawings")
		(19 "Cmts.User" user "User.Comments")
		(21 "Eco1.User" user "User.Eco1")
		(23 "Eco2.User" user "User.Eco2")
		(25 "Edge.Cuts" user "Board Geometry/Outline")
		(27 "Margin" user)
		(31 "F.CrtYd" user "Package Geometry/Place Bound Top")
		(29 "B.CrtYd" user "Package Geometry/Place Bound Bottom")
		(35 "F.Fab" user "Ref Des/Assembly Top")
		(33 "B.Fab" user "Ref Des/Assembly Bottom")
	)
	(footprint ""
		(layer "B.Cu")
		(at 389.349996 -30.550104 180)
		(property "Reference" "IO2"
			(at 0 0 0)
			(layer "B.SilkS")
			(hide yes)
			(effects
				(font
					(size 1.27 1.27)
				)
				(justify mirror)
			)
		)
		(property "Value" "DM-AMP-CONN200-13R-6-GP-01"
			(at 47.5488 -16.5862 180)
			(unlocked yes)
			(layer "B.Fab")
			(hide yes)
			(effects
				(font
					(size 1.016 1.016)
					(thickness 0.1524)
				)
				(justify mirror)
			)
		)
		(property "Device Type" "DMFIT-200P-384346H577-01"
			(at 47.5488 -18.1102 180)
			(unlocked yes)
			(layer "B.Fab")
			(hide yes)
			(effects
				(font
					(size 1.016 1.016)
					(thickness 0.1524)
				)
				(justify mirror)
			)
		)
		(duplicate_pad_numbers_are_jumpers no)
		(pad "H11" thru_hole circle
			(at 25.200102 -12.199874)
			(size 0.664718 0.664718)
			(drill 0.359918)
			(layers "*.Cu" "*.Mask")
			(remove_unused_layers no)
			(net "PCIE_COMP_B_TO_IOM_B_21_DP")
			(clearance 0.264414)
			(padstack
				(mode custom)
				(layer "In1.Cu"
					(shape circle)
					(size 0.664718 0.664718)
					(clearance 0.264414)
				)
				(layer "In2.Cu"
					(shape circle)
					(size 0.664718 0.664718)
					(clearance 0.264414)
				)
				(layer "In3.Cu"
					(shape circle)
					(size 0.664718 0.664718)
					(clearance 0.264414)
				)
				(layer "In4.Cu"
					(shape circle)
					(size 0.664718 0.664718)
					(clearance 0.264414)
				)
				(layer "In5.Cu"
					(shape circle)
					(size 0.664718 0.664718)
					(clearance 0.264414)
				)
				(layer "In6.Cu"
					(shape circle)
					(size 0.762 0.762)
					(clearance 0.1651)
				)
				(layer "In7.Cu"
					(shape circle)
					(size 0.762 0.762)
					(clearance 0.1651)
				)
				(layer "In8.Cu"
					(shape circle)
					(size 0.762 0.762)
					(clearance 0.1651)
				)
				(layer "In9.Cu"
					(shape circle)
					(size 0.762 0.762)
					(clearance 0.1651)
				)
				(layer "In10.Cu"
					(shape circle)
					(size 0.762 0.762)
					(clearance 0.1651)
				)
				(layer "B.Cu"
					(shape circle)
					(size 0.762 0.762)
					(thermal_gap 0.1651)
					(clearance 0.1651)
				)
			)
		)
		(pad "H12" thru_hole circle
			(at 26.999946 -13.200126)
			(size 0.664718 0.664718)
			(drill 0.359918)
			(layers "*.Cu" "*.Mask")
			(remove_unused_layers no)
			(net "PCIE_COMP_B_TO_IOM_B_20_DP")
			(clearance 0.264414)
			(padstack
				(mode custom)
				(layer "In1.Cu"
					(shape circle)
					(size 0.664718 0.664718)
					(clearance 0.264414)
				)
				(layer "In2.Cu"
					(shape circle)
					(size 0.664718 0.664718)
					(clearance 0.264414)
				)
				(layer "In3.Cu"
					(shape circle)
					(size 0.664718 0.664718)
					(clearance 0.264414)
				)
				(layer "In4.Cu"
					(shape circle)
					(size 0.664718 0.664718)
					(clearance 0.264414)
				)
				(layer "In5.Cu"
					(shape circle)
					(size 0.664718 0.664718)
					(clearance 0.264414)
				)
				(layer "In6.Cu"
					(shape circle)
					(size 0.762 0.762)
					(clearance 0.1651)
				)
				(layer "In7.Cu"
					(shape circle)
					(size 0.762 0.762)
					(clearance 0.1651)
				)
				(layer "In8.Cu"
					(shape circle)
					(size 0.762 0.762)
					(clearance 0.1651)
				)
				(layer "In9.Cu"
					(shape circle)
					(size 0.762 0.762)
					(clearance 0.1651)
				)
				(layer "In10.Cu"
					(shape circle)
					(size 0.762 0.762)
					(clearance 0.1651)
				)
				(layer "B.Cu"
					(shape circle)
					(size 0.762 0.762)
					(thermal_gap 0.1651)
					(clearance 0.1651)
				)
			)
		)
		(pad "H13" thru_hole circle
			(at 28.800044 -12.199874)
			(size 0.664718 0.664718)
			(drill 0.359918)
			(layers "*.Cu" "*.Mask")
			(remove_unused_layers no)
			(net "PCIE_COMP_B_TO_IOM_B_19_DP")
			(clearance 0.264414)
			(padstack
				(mode custom)
				(layer "In1.Cu"
					(shape circle)
					(size 0.664718 0.664718)
					(clearance 0.264414)
				)
				(layer "In2.Cu"
					(shape circle)
					(size 0.664718 0.664718)
					(clearance 0.264414)
				)
				(layer "In3.Cu"
					(shape circle)
					(size 0.664718 0.664718)
					(clearance 0.264414)
				)
				(layer "In4.Cu"
					(shape circle)
					(size 0.664718 0.664718)
					(clearance 0.264414)
				)
				(layer "In5.Cu"
					(shape circle)
					(size 0.664718 0.664718)
					(clearance 0.264414)
				)
				(layer "In6.Cu"
					(shape circle)
					(size 0.762 0.762)
					(clearance 0.1651)
				)
				(layer "In7.Cu"
					(shape circle)
					(size 0.762 0.762)
					(clearance 0.1651)
				)
				(layer "In8.Cu"
					(shape circle)
					(size 0.762 0.762)
					(clearance 0.1651)
				)
				(layer "In9.Cu"
					(shape circle)
					(size 0.762 0.762)
					(clearance 0.1651)
				)
				(layer "In10.Cu"
					(shape circle)
					(size 0.762 0.762)
					(clearance 0.1651)
				)
				(layer "B.Cu"
					(shape circle)
					(size 0.762 0.762)
					(thermal_gap 0.1651)
					(clearance 0.1651)
				)
			)
		)
		(pad "H14" thru_hole circle
			(at 30.599888 -13.200126)
			(size 0.664718 0.664718)
			(drill 0.359918)
			(layers "*.Cu" "*.Mask")
			(remove_unused_layers no)
			(net "PCIE_COMP_B_TO_IOM_B_18_DP")
			(clearance 0.264414)
			(padstack
				(mode custom)
				(layer "In1.Cu"
					(shape circle)
					(size 0.664718 0.664718)
					(clearance 0.264414)
				)
				(layer "In2.Cu"
					(shape circle)
					(size 0.664718 0.664718)
					(clearance 0.264414)
				)
				(layer "In3.Cu"
					(shape circle)
					(size 0.664718 0.664718)
					(clearance 0.264414)
				)
				(layer "In4.Cu"
					(shape circle)
					(size 0.664718 0.664718)
					(clearance 0.264414)
				)
				(layer "In5.Cu"
					(shape circle)
					(size 0.664718 0.664718)
					(clearance 0.264414)
				)
				(layer "In6.Cu"
					(shape circle)
					(size 0.762 0.762)
					(clearance 0.1651)
				)
				(layer "In7.Cu"
					(shape circle)
					(size 0.762 0.762)
					(clearance 0.1651)
				)
				(layer "In8.Cu"
					(shape circle)
					(size 0.762 0.762)
					(clearance 0.1651)
				)
				(layer "In9.Cu"
					(shape circle)
					(size 0.762 0.762)
					(clearance 0.1651)
				)
				(layer "In10.Cu"
					(shape circle)
					(size 0.762 0.762)
					(clearance 0.1651)
				)
				(layer "B.Cu"
					(shape circle)
					(size 0.762 0.762)
					(thermal_gap 0.1651)
					(clearance 0.1651)
				)
			)
		)
		(pad "H15" thru_hole circle
			(at 32.399986 -12.199874)
			(size 0.664718 0.664718)
			(drill 0.359918)
			(layers "*.Cu" "*.Mask")
			(remove_unused_layers no)
			(net "PCIE_COMP_B_TO_IOM_B_17_DP")
			(clearance 0.264414)
			(padstack
				(mode custom)
				(layer "In1.Cu"
					(shape circle)
					(size 0.664718 0.664718)
					(clearance 0.264414)
				)
				(layer "In2.Cu"
					(shape circle)
					(size 0.664718 0.664718)
					(clearance 0.264414)
				)
				(layer "In3.Cu"
					(shape circle)
					(size 0.664718 0.664718)
					(clearance 0.264414)
				)
				(layer "In4.Cu"
					(shape circle)
					(size 0.664718 0.664718)
					(clearance 0.264414)
				)
				(layer "In5.Cu"
					(shape circle)
					(size 0.664718 0.664718)
					(clearance 0.264414)
				)
				(layer "In6.Cu"
					(shape circle)
					(size 0.762 0.762)
					(clearance 0.1651)
				)
				(layer "In7.Cu"
					(shape circle)
					(size 0.762 0.762)
					(clearance 0.1651)
				)
				(layer "In8.Cu"
					(shape circle)
					(size 0.762 0.762)
					(clearance 0.1651)
				)
				(layer "In9.Cu"
					(shape circle)
					(size 0.762 0.762)
					(clearance 0.1651)
				)
				(layer "In10.Cu"
					(shape circle)
					(size 0.762 0.762)
					(clearance 0.1651)
				)
				(layer "B.Cu"
					(shape circle)
					(size 0.762 0.762)
					(thermal_gap 0.1651)
					(clearance 0.1651)
				)
			)
		)
		(pad "H16" thru_hole circle
			(at 34.200084 -13.200126)
			(size 0.664718 0.664718)
			(drill 0.359918)
			(layers "*.Cu" "*.Mask")
			(remove_unused_layers no)
			(net "PCIE_COMP_B_TO_IOM_B_16_DP")
			(clearance 0.264414)
			(padstack
				(mode custom)
				(layer "In1.Cu"
					(shape circle)
					(size 0.664718 0.664718)
					(clearance 0.264414)
				)
				(layer "In2.Cu"
					(shape circle)
					(size 0.664718 0.664718)
					(clearance 0.264414)
				)
				(layer "In3.Cu"
					(shape circle)
					(size 0.664718 0.664718)
					(clearance 0.264414)
				)
				(layer "In4.Cu"
					(shape circle)
					(size 0.664718 0.664718)
					(clearance 0.264414)
				)
				(layer "In5.Cu"
					(shape circle)
					(size 0.664718 0.664718)
					(clearance 0.264414)
				)
				(layer "In6.Cu"
					(shape circle)
					(size 0.762 0.762)
					(clearance 0.1651)
				)
				(layer "In7.Cu"
					(shape circle)
					(size 0.762 0.762)
					(clearance 0.1651)
				)
				(layer "In8.Cu"
					(shape circle)
					(size 0.762 0.762)
					(clearance 0.1651)
				)
				(layer "In9.Cu"
					(shape circle)
					(size 0.762 0.762)
					(clearance 0.1651)
				)
				(layer "In10.Cu"
					(shape circle)
					(size 0.762 0.762)
					(clearance 0.1651)
				)
				(layer "B.Cu"
					(shape circle)
					(size 0.762 0.762)
					(thermal_gap 0.1651)
					(clearance 0.1651)
				)
			)
		)
	)
)
